(kicad_pcb
	(version 20260206)
	(generator "pcbnew")
	(generator_version "10.0")
	(general
		(thickness 1.6)
		(legacy_teardrops no)
	)
	(paper "A4")
	(title_block
		(title "04192023_DAF0TMB3IC0_F0TG_MB_C_brd_V02_OCP.brd")
		(comment 1 "Grand Teton / footprints 6581-6587 of 8354")
	)
	(layers
		(0 "F.Cu" signal "TOP")
		(4 "In1.Cu" signal "GND")
		(6 "In2.Cu" signal "IN1")
		(8 "In3.Cu" signal "GND1")
		(10 "In4.Cu" signal "IN2")
		(12 "In5.Cu" signal "GND2")
		(14 "In6.Cu" signal "IN3")
		(16 "In7.Cu" signal "GND3")
		(18 "In8.Cu" signal "VCC")
		(20 "In9.Cu" signal "VCC1")
		(22 "In10.Cu" signal "GND4")
		(24 "In11.Cu" signal "IN4")
		(26 "In12.Cu" signal "GND5")
		(28 "In13.Cu" signal "IN5")
		(30 "In14.Cu" signal "GND6")
		(32 "In15.Cu" signal "IN6")
		(34 "In16.Cu" signal "GND7")
		(2 "B.Cu" signal "BOTTOM")
		(9 "F.Adhes" user "F.Adhesive")
		(11 "B.Adhes" user "B.Adhesive")
		(13 "F.Paste" user "Package Geometry/Pastemask Top")
		(15 "B.Paste" user "Package Geometry/Pastemask Bottom")
		(5 "F.SilkS" user "Ref Des/Silkscreen Top")
		(7 "B.SilkS" user "Ref Des/Silkscreen Bottom")
		(1 "F.Mask" user "Board Geometry/Soldermask Top")
		(3 "B.Mask" user "Board Geometry/Soldermask Bottom")
		(17 "Dwgs.User" user "User.Drawings")
		(19 "Cmts.User" user "User.Comments")
		(21 "Eco1.User" user "User.Eco1")
		(23 "Eco2.User" user "User.Eco2")
		(25 "Edge.Cuts" user "Board Geometry/Outline")
		(27 "Margin" user)
		(31 "F.CrtYd" user "Package Geometry/Place Bound Top")
		(29 "B.CrtYd" user "Package Geometry/Place Bound Bottom")
		(35 "F.Fab" user "Ref Des/Assembly Top")
		(33 "B.Fab" user "Ref Des/Assembly Bottom")
	)
	(footprint ""
		(layer "B.Cu")
		(at 310.590946 -398.942052 90)
		(property "Reference" "C574"
			(at 0 0 90)
			(layer "B.SilkS")
			(hide yes)
			(effects
				(font
					(size 1.27 1.27)
				)
				(justify mirror)
			)
		)
		(property "Value" ""
			(at 0 0 90)
			(layer "B.Fab")
			(effects
				(font
					(size 1.27 1.27)
				)
				(justify mirror)
			)
		)
		(duplicate_pad_numbers_are_jumpers no)
		(fp_line
			(start 0.7874 -0.4064)
			(end -0.7874 -0.4064)
			(stroke
				(width 0.1524)
				(type default)
			)
			(layer "B.SilkS")
		)
		(fp_line
			(start -0.7874 -0.4064)
			(end -0.7874 0.4064)
			(stroke
				(width 0.1524)
				(type default)
			)
			(layer "B.SilkS")
		)
		(fp_line
			(start 0.7874 0.4064)
			(end 0.7874 -0.4064)
			(stroke
				(width 0.1524)
				(type default)
			)
			(layer "B.SilkS")
		)
		(fp_line
			(start -0.7874 0.4064)
			(end 0.7874 0.4064)
			(stroke
				(width 0.1524)
				(type default)
			)
			(layer "B.SilkS")
		)
		(fp_line
			(start 0.67945 -0.305054)
			(end 0.12065 -0.305054)
			(stroke
				(width 0.1)
				(type default)
			)
			(layer "B.Fab")
		)
		(fp_line
			(start 0.12065 -0.305054)
			(end 0.12065 -0.2794)
			(stroke
				(width 0.1)
				(type default)
			)
			(layer "B.Fab")
		)
		(fp_line
			(start -0.12065 -0.3048)
			(end -0.67945 -0.3048)
			(stroke
				(width 0.1)
				(type default)
			)
			(layer "B.Fab")
		)
		(fp_line
			(start -0.67945 -0.3048)
			(end -0.67945 0.3048)
			(stroke
				(width 0.1)
				(type default)
			)
			(layer "B.Fab")
		)
		(fp_line
			(start 0.12065 -0.2794)
			(end -0.12065 -0.2794)
			(stroke
				(width 0.1)
				(type default)
			)
			(layer "B.Fab")
		)
		(fp_line
			(start -0.12065 -0.2794)
			(end -0.12065 -0.3048)
			(stroke
				(width 0.1)
				(type default)
			)
			(layer "B.Fab")
		)
		(fp_line
			(start 0.12065 0.2794)
			(end 0.12065 0.3048)
			(stroke
				(width 0.1)
				(type default)
			)
			(layer "B.Fab")
		)
		(fp_line
			(start -0.120396 0.2794)
			(end 0.12065 0.2794)
			(stroke
				(width 0.1)
				(type default)
			)
			(layer "B.Fab")
		)
		(fp_line
			(start 0.67945 0.3048)
			(end 0.67945 -0.305054)
			(stroke
				(width 0.1)
				(type default)
			)
			(layer "B.Fab")
		)
		(fp_line
			(start 0.12065 0.3048)
			(end 0.67945 0.3048)
			(stroke
				(width 0.1)
				(type default)
			)
			(layer "B.Fab")
		)
		(fp_line
			(start -0.120396 0.3048)
			(end -0.120396 0.2794)
			(stroke
				(width 0.1)
				(type default)
			)
			(layer "B.Fab")
		)
		(fp_line
			(start -0.67945 0.3048)
			(end -0.120396 0.3048)
			(stroke
				(width 0.1)
				(type default)
			)
			(layer "B.Fab")
		)
		(pad "1" smd circle
			(at 0.40005 0 270)
			(size 0 0)
			(layers "B.Cu" "B.Mask" "B.Paste")
			(net "P0V9_CPU0_RT_2D")
		)
		(pad "2" smd circle
			(at -0.40005 0 270)
			(size 0 0)
			(layers "B.Cu" "B.Mask" "B.Paste")
			(net "GND")
		)
	)
	(footprint ""
		(layer "B.Cu")
		(at 96.163384 -408.517344 90)
		(property "Reference" "C6691"
			(at 0 0 90)
			(layer "B.SilkS")
			(hide yes)
			(effects
				(font
					(size 1.27 1.27)
				)
				(justify mirror)
			)
		)
		(property "Value" ""
			(at 0 0 90)
			(layer "B.Fab")
			(effects
				(font
					(size 1.27 1.27)
				)
				(justify mirror)
			)
		)
		(duplicate_pad_numbers_are_jumpers no)
		(fp_line
			(start 0.299974 -0.150114)
			(end -0.299974 -0.150114)
			(stroke
				(width 0.1)
				(type default)
			)
			(layer "B.Fab")
		)
		(fp_line
			(start -0.299974 -0.150114)
			(end -0.299974 0.150114)
			(stroke
				(width 0.1)
				(type default)
			)
			(layer "B.Fab")
		)
		(fp_line
			(start 0.299974 0.150114)
			(end 0.299974 -0.150114)
			(stroke
				(width 0.1)
				(type default)
			)
			(layer "B.Fab")
		)
		(fp_line
			(start -0.299974 0.150114)
			(end 0.299974 0.150114)
			(stroke
				(width 0.1)
				(type default)
			)
			(layer "B.Fab")
		)
		(pad "1" smd rect
			(at 0.2667 0 270)
			(size 0.3048 0.381)
			(layers "B.Cu" "B.Mask" "B.Paste")
			(net "P5E_CPU1_P1_TX_BUF_C_DP<15>")
		)
		(pad "2" smd rect
			(at -0.2667 0 270)
			(size 0.3048 0.381)
			(layers "B.Cu" "B.Mask" "B.Paste")
			(net "P5E_CPU1_P1_TX_BUF_DP<15>")
		)
	)
	(footprint ""
		(layer "B.Cu")
		(at 183.364886 -133.795008 -90)
		(property "Reference" "R1288"
			(at 0 0 90)
			(layer "B.SilkS")
			(hide yes)
			(effects
				(font
					(size 1.27 1.27)
				)
				(justify mirror)
			)
		)
		(property "Value" ""
			(at 0 0 90)
			(layer "B.Fab")
			(effects
				(font
					(size 1.27 1.27)
				)
				(justify mirror)
			)
		)
		(duplicate_pad_numbers_are_jumpers no)
		(fp_line
			(start -0.7874 0.4064)
			(end 0.7874 0.4064)
			(stroke
				(width 0.1524)
				(type default)
			)
			(layer "B.SilkS")
		)
		(fp_line
			(start 0.7874 0.4064)
			(end 0.7874 -0.4064)
			(stroke
				(width 0.1524)
				(type default)
			)
			(layer "B.SilkS")
		)
		(fp_line
			(start -0.7874 -0.4064)
			(end -0.7874 0.4064)
			(stroke
				(width 0.1524)
				(type default)
			)
			(layer "B.SilkS")
		)
		(fp_line
			(start 0.7874 -0.4064)
			(end -0.7874 -0.4064)
			(stroke
				(width 0.1524)
				(type default)
			)
			(layer "B.SilkS")
		)
		(fp_line
			(start -0.67945 0.3048)
			(end -0.120396 0.3048)
			(stroke
				(width 0.1)
				(type default)
			)
			(layer "B.Fab")
		)
		(fp_line
			(start -0.120396 0.3048)
			(end -0.120396 0.2794)
			(stroke
				(width 0.1)
				(type default)
			)
			(layer "B.Fab")
		)
		(fp_line
			(start 0.12065 0.3048)
			(end 0.67945 0.3048)
			(stroke
				(width 0.1)
				(type default)
			)
			(layer "B.Fab")
		)
		(fp_line
			(start 0.67945 0.3048)
			(end 0.67945 -0.305054)
			(stroke
				(width 0.1)
				(type default)
			)
			(layer "B.Fab")
		)
		(fp_line
			(start -0.120396 0.2794)
			(end 0.12065 0.2794)
			(stroke
				(width 0.1)
				(type default)
			)
			(layer "B.Fab")
		)
		(fp_line
			(start 0.12065 0.2794)
			(end 0.12065 0.3048)
			(stroke
				(width 0.1)
				(type default)
			)
			(layer "B.Fab")
		)
		(fp_line
			(start -0.12065 -0.2794)
			(end -0.12065 -0.3048)
			(stroke
				(width 0.1)
				(type default)
			)
			(layer "B.Fab")
		)
		(fp_line
			(start 0.12065 -0.2794)
			(end -0.12065 -0.2794)
			(stroke
				(width 0.1)
				(type default)
			)
			(layer "B.Fab")
		)
		(fp_line
			(start -0.67945 -0.3048)
			(end -0.67945 0.3048)
			(stroke
				(width 0.1)
				(type default)
			)
			(layer "B.Fab")
		)
		(fp_line
			(start -0.12065 -0.3048)
			(end -0.67945 -0.3048)
			(stroke
				(width 0.1)
				(type default)
			)
			(layer "B.Fab")
		)
		(fp_line
			(start 0.12065 -0.305054)
			(end 0.12065 -0.2794)
			(stroke
				(width 0.1)
				(type default)
			)
			(layer "B.Fab")
		)
		(fp_line
			(start 0.67945 -0.305054)
			(end 0.12065 -0.305054)
			(stroke
				(width 0.1)
				(type default)
			)
			(layer "B.Fab")
		)
		(pad "1" smd circle
			(at 0.40005 0 90)
			(size 0 0)
			(layers "B.Cu" "B.Mask" "B.Paste")
			(net "FM_P0_PCC1_N")
		)
		(pad "2" smd circle
			(at -0.40005 0 90)
			(size 0 0)
			(layers "B.Cu" "B.Mask" "B.Paste")
			(net "PVDD18_S5_P0")
		)
	)
	(footprint ""
		(layer "B.Cu")
		(at 348.004638 -342.599772 -90)
		(property "Reference" "PR421"
			(at 0 0 90)
			(layer "B.SilkS")
			(hide yes)
			(effects
				(font
					(size 1.27 1.27)
				)
				(justify mirror)
			)
		)
		(property "Value" ""
			(at 0 0 90)
			(layer "B.Fab")
			(effects
				(font
					(size 1.27 1.27)
				)
				(justify mirror)
			)
		)
		(duplicate_pad_numbers_are_jumpers no)
		(fp_line
			(start -0.7874 0.4064)
			(end 0.7874 0.4064)
			(stroke
				(width 0.1524)
				(type default)
			)
			(layer "B.SilkS")
		)
		(fp_line
			(start 0.7874 0.4064)
			(end 0.7874 -0.4064)
			(stroke
				(width 0.1524)
				(type default)
			)
			(layer "B.SilkS")
		)
		(fp_line
			(start -0.7874 -0.4064)
			(end -0.7874 0.4064)
			(stroke
				(width 0.1524)
				(type default)
			)
			(layer "B.SilkS")
		)
		(fp_line
			(start 0.7874 -0.4064)
			(end -0.7874 -0.4064)
			(stroke
				(width 0.1524)
				(type default)
			)
			(layer "B.SilkS")
		)
		(fp_line
			(start -0.67945 0.3048)
			(end -0.120396 0.3048)
			(stroke
				(width 0.1)
				(type default)
			)
			(layer "B.Fab")
		)
		(fp_line
			(start -0.120396 0.3048)
			(end -0.120396 0.2794)
			(stroke
				(width 0.1)
				(type default)
			)
			(layer "B.Fab")
		)
		(fp_line
			(start 0.12065 0.3048)
			(end 0.67945 0.3048)
			(stroke
				(width 0.1)
				(type default)
			)
			(layer "B.Fab")
		)
		(fp_line
			(start 0.67945 0.3048)
			(end 0.67945 -0.305054)
			(stroke
				(width 0.1)
				(type default)
			)
			(layer "B.Fab")
		)
		(fp_line
			(start -0.120396 0.2794)
			(end 0.12065 0.2794)
			(stroke
				(width 0.1)
				(type default)
			)
			(layer "B.Fab")
		)
		(fp_line
			(start 0.12065 0.2794)
			(end 0.12065 0.3048)
			(stroke
				(width 0.1)
				(type default)
			)
			(layer "B.Fab")
		)
		(fp_line
			(start -0.12065 -0.2794)
			(end -0.12065 -0.3048)
			(stroke
				(width 0.1)
				(type default)
			)
			(layer "B.Fab")
		)
		(fp_line
			(start 0.12065 -0.2794)
			(end -0.12065 -0.2794)
			(stroke
				(width 0.1)
				(type default)
			)
			(layer "B.Fab")
		)
		(fp_line
			(start -0.67945 -0.3048)
			(end -0.67945 0.3048)
			(stroke
				(width 0.1)
				(type default)
			)
			(layer "B.Fab")
		)
		(fp_line
			(start -0.12065 -0.3048)
			(end -0.67945 -0.3048)
			(stroke
				(width 0.1)
				(type default)
			)
			(layer "B.Fab")
		)
		(fp_line
			(start 0.12065 -0.305054)
			(end 0.12065 -0.2794)
			(stroke
				(width 0.1)
				(type default)
			)
			(layer "B.Fab")
		)
		(fp_line
			(start 0.67945 -0.305054)
			(end 0.12065 -0.305054)
			(stroke
				(width 0.1)
				(type default)
			)
			(layer "B.Fab")
		)
		(pad "1" smd circle
			(at 0.40005 0 90)
			(size 0 0)
			(layers "B.Cu" "B.Mask" "B.Paste")
			(net "PVDDCR_CPU1_P0_VOS6")
		)
		(pad "2" smd circle
			(at -0.40005 0 90)
			(size 0 0)
			(layers "B.Cu" "B.Mask" "B.Paste")
			(net "PVDDCR_CPU1_P0")
		)
	)
	(footprint ""
		(layer "B.Cu")
		(at 243.713 -323.85)
		(property "Reference" "C1080"
			(at 0 0 0)
			(layer "B.SilkS")
			(hide yes)
			(effects
				(font
					(size 1.27 1.27)
				)
				(justify mirror)
			)
		)
		(property "Value" ""
			(at 0 0 0)
			(layer "B.Fab")
			(effects
				(font
					(size 1.27 1.27)
				)
				(justify mirror)
			)
		)
		(duplicate_pad_numbers_are_jumpers no)
		(fp_line
			(start -0.7874 -0.4064)
			(end -0.7874 0.4064)
			(stroke
				(width 0.1524)
				(type default)
			)
			(layer "B.SilkS")
		)
		(fp_line
			(start -0.7874 0.4064)
			(end 0.7874 0.4064)
			(stroke
				(width 0.1524)
				(type default)
			)
			(layer "B.SilkS")
		)
		(fp_line
			(start 0.7874 -0.4064)
			(end -0.7874 -0.4064)
			(stroke
				(width 0.1524)
				(type default)
			)
			(layer "B.SilkS")
		)
		(fp_line
			(start 0.7874 0.4064)
			(end 0.7874 -0.4064)
			(stroke
				(width 0.1524)
				(type default)
			)
			(layer "B.SilkS")
		)
		(fp_line
			(start -0.67945 -0.3048)
			(end -0.67945 0.3048)
			(stroke
				(width 0.1)
				(type default)
			)
			(layer "B.Fab")
		)
		(fp_line
			(start -0.67945 0.3048)
			(end -0.120396 0.3048)
			(stroke
				(width 0.1)
				(type default)
			)
			(layer "B.Fab")
		)
		(fp_line
			(start -0.12065 -0.3048)
			(end -0.67945 -0.3048)
			(stroke
				(width 0.1)
				(type default)
			)
			(layer "B.Fab")
		)
		(fp_line
			(start -0.12065 -0.2794)
			(end -0.12065 -0.3048)
			(stroke
				(width 0.1)
				(type default)
			)
			(layer "B.Fab")
		)
		(fp_line
			(start -0.120396 0.2794)
			(end 0.12065 0.2794)
			(stroke
				(width 0.1)
				(type default)
			)
			(layer "B.Fab")
		)
		(fp_line
			(start -0.120396 0.3048)
			(end -0.120396 0.2794)
			(stroke
				(width 0.1)
				(type default)
			)
			(layer "B.Fab")
		)
		(fp_line
			(start 0.12065 -0.305054)
			(end 0.12065 -0.2794)
			(stroke
				(width 0.1)
				(type default)
			)
			(layer "B.Fab")
		)
		(fp_line
			(start 0.12065 -0.2794)
			(end -0.12065 -0.2794)
			(stroke
				(width 0.1)
				(type default)
			)
			(layer "B.Fab")
		)
		(fp_line
			(start 0.12065 0.2794)
			(end 0.12065 0.3048)
			(stroke
				(width 0.1)
				(type default)
			)
			(layer "B.Fab")
		)
		(fp_line
			(start 0.12065 0.3048)
			(end 0.67945 0.3048)
			(stroke
				(width 0.1)
				(type default)
			)
			(layer "B.Fab")
		)
		(fp_line
			(start 0.67945 -0.305054)
			(end 0.12065 -0.305054)
			(stroke
				(width 0.1)
				(type default)
			)
			(layer "B.Fab")
		)
		(fp_line
			(start 0.67945 0.3048)
			(end 0.67945 -0.305054)
			(stroke
				(width 0.1)
				(type default)
			)
			(layer "B.Fab")
		)
		(pad "1" smd circle
			(at 0.40005 0 180)
			(size 0 0)
			(layers "B.Cu" "B.Mask" "B.Paste")
			(net "PVDD18_S5_P0_ADC_MAM")
		)
		(pad "2" smd circle
			(at -0.40005 0 180)
			(size 0 0)
			(layers "B.Cu" "B.Mask" "B.Paste")
			(net "GND")
		)
	)
	(footprint ""
		(layer "B.Cu")
		(at 239.395 -234.061 -90)
		(property "Reference" "R144"
			(at 0 0 90)
			(layer "B.SilkS")
			(hide yes)
			(effects
				(font
					(size 1.27 1.27)
				)
				(justify mirror)
			)
		)
		(property "Value" ""
			(at 0 0 90)
			(layer "B.Fab")
			(effects
				(font
					(size 1.27 1.27)
				)
				(justify mirror)
			)
		)
		(duplicate_pad_numbers_are_jumpers no)
		(fp_line
			(start -0.7874 0.4064)
			(end 0.7874 0.4064)
			(stroke
				(width 0.1524)
				(type default)
			)
			(layer "B.SilkS")
		)
		(fp_line
			(start 0.7874 0.4064)
			(end 0.7874 -0.4064)
			(stroke
				(width 0.1524)
				(type default)
			)
			(layer "B.SilkS")
		)
		(fp_line
			(start -0.7874 -0.4064)
			(end -0.7874 0.4064)
			(stroke
				(width 0.1524)
				(type default)
			)
			(layer "B.SilkS")
		)
		(fp_line
			(start 0.7874 -0.4064)
			(end -0.7874 -0.4064)
			(stroke
				(width 0.1524)
				(type default)
			)
			(layer "B.SilkS")
		)
		(fp_line
			(start -0.67945 0.3048)
			(end -0.120396 0.3048)
			(stroke
				(width 0.1)
				(type default)
			)
			(layer "B.Fab")
		)
		(fp_line
			(start -0.120396 0.3048)
			(end -0.120396 0.2794)
			(stroke
				(width 0.1)
				(type default)
			)
			(layer "B.Fab")
		)
		(fp_line
			(start 0.12065 0.3048)
			(end 0.67945 0.3048)
			(stroke
				(width 0.1)
				(type default)
			)
			(layer "B.Fab")
		)
		(fp_line
			(start 0.67945 0.3048)
			(end 0.67945 -0.305054)
			(stroke
				(width 0.1)
				(type default)
			)
			(layer "B.Fab")
		)
		(fp_line
			(start -0.120396 0.2794)
			(end 0.12065 0.2794)
			(stroke
				(width 0.1)
				(type default)
			)
			(layer "B.Fab")
		)
		(fp_line
			(start 0.12065 0.2794)
			(end 0.12065 0.3048)
			(stroke
				(width 0.1)
				(type default)
			)
			(layer "B.Fab")
		)
		(fp_line
			(start -0.12065 -0.2794)
			(end -0.12065 -0.3048)
			(stroke
				(width 0.1)
				(type default)
			)
			(layer "B.Fab")
		)
		(fp_line
			(start 0.12065 -0.2794)
			(end -0.12065 -0.2794)
			(stroke
				(width 0.1)
				(type default)
			)
			(layer "B.Fab")
		)
		(fp_line
			(start -0.67945 -0.3048)
			(end -0.67945 0.3048)
			(stroke
				(width 0.1)
				(type default)
			)
			(layer "B.Fab")
		)
		(fp_line
			(start -0.12065 -0.3048)
			(end -0.67945 -0.3048)
			(stroke
				(width 0.1)
				(type default)
			)
			(layer "B.Fab")
		)
		(fp_line
			(start 0.12065 -0.305054)
			(end 0.12065 -0.2794)
			(stroke
				(width 0.1)
				(type default)
			)
			(layer "B.Fab")
		)
		(fp_line
			(start 0.67945 -0.305054)
			(end 0.12065 -0.305054)
			(stroke
				(width 0.1)
				(type default)
			)
			(layer "B.Fab")
		)
		(pad "1" smd circle
			(at 0.40005 0 90)
			(size 0 0)
			(layers "B.Cu" "B.Mask" "B.Paste")
			(net "SMB_CPU0_CPU1_SEC_SDA_R2")
		)
		(pad "2" smd circle
			(at -0.40005 0 90)
			(size 0 0)
			(layers "B.Cu" "B.Mask" "B.Paste")
			(net "SMB_CPU0_SEC_R_SDA")
		)
	)
	(footprint ""
		(layer "B.Cu")
		(at 15.448788 -132.78993 90)
		(property "Reference" "C1884"
			(at 0 0 90)
			(layer "B.SilkS")
			(hide yes)
			(effects
				(font
					(size 1.27 1.27)
				)
				(justify mirror)
			)
		)
		(property "Value" ""
			(at 0 0 90)
			(layer "B.Fab")
			(effects
				(font
					(size 1.27 1.27)
				)
				(justify mirror)
			)
		)
		(duplicate_pad_numbers_are_jumpers no)
		(fp_line
			(start 0.7874 -0.4064)
			(end -0.7874 -0.4064)
			(stroke
				(width 0.1524)
				(type default)
			)
			(layer "B.SilkS")
		)
		(fp_line
			(start -0.7874 -0.4064)
			(end -0.7874 0.4064)
			(stroke
				(width 0.1524)
				(type default)
			)
			(layer "B.SilkS")
		)
		(fp_line
			(start 0.7874 0.4064)
			(end 0.7874 -0.4064)
			(stroke
				(width 0.1524)
				(type default)
			)
			(layer "B.SilkS")
		)
		(fp_line
			(start -0.7874 0.4064)
			(end 0.7874 0.4064)
			(stroke
				(width 0.1524)
				(type default)
			)
			(layer "B.SilkS")
		)
		(fp_line
			(start 0.67945 -0.305054)
			(end 0.12065 -0.305054)
			(stroke
				(width 0.1)
				(type default)
			)
			(layer "B.Fab")
		)
		(fp_line
			(start 0.12065 -0.305054)
			(end 0.12065 -0.2794)
			(stroke
				(width 0.1)
				(type default)
			)
			(layer "B.Fab")
		)
		(fp_line
			(start -0.12065 -0.3048)
			(end -0.67945 -0.3048)
			(stroke
				(width 0.1)
				(type default)
			)
			(layer "B.Fab")
		)
		(fp_line
			(start -0.67945 -0.3048)
			(end -0.67945 0.3048)
			(stroke
				(width 0.1)
				(type default)
			)
			(layer "B.Fab")
		)
		(fp_line
			(start 0.12065 -0.2794)
			(end -0.12065 -0.2794)
			(stroke
				(width 0.1)
				(type default)
			)
			(layer "B.Fab")
		)
		(fp_line
			(start -0.12065 -0.2794)
			(end -0.12065 -0.3048)
			(stroke
				(width 0.1)
				(type default)
			)
			(layer "B.Fab")
		)
		(fp_line
			(start 0.12065 0.2794)
			(end 0.12065 0.3048)
			(stroke
				(width 0.1)
				(type default)
			)
			(layer "B.Fab")
		)
		(fp_line
			(start -0.120396 0.2794)
			(end 0.12065 0.2794)
			(stroke
				(width 0.1)
				(type default)
			)
			(layer "B.Fab")
		)
		(fp_line
			(start 0.67945 0.3048)
			(end 0.67945 -0.305054)
			(stroke
				(width 0.1)
				(type default)
			)
			(layer "B.Fab")
		)
		(fp_line
			(start 0.12065 0.3048)
			(end 0.67945 0.3048)
			(stroke
				(width 0.1)
				(type default)
			)
			(layer "B.Fab")
		)
		(fp_line
			(start -0.120396 0.3048)
			(end -0.120396 0.2794)
			(stroke
				(width 0.1)
				(type default)
			)
			(layer "B.Fab")
		)
		(fp_line
			(start -0.67945 0.3048)
			(end -0.120396 0.3048)
			(stroke
				(width 0.1)
				(type default)
			)
			(layer "B.Fab")
		)
		(pad "1" smd circle
			(at 0.40005 0 270)
			(size 0 0)
			(layers "B.Cu" "B.Mask" "B.Paste")
			(net "VFG_3P3A_CLK_GEN")
		)
		(pad "2" smd circle
			(at -0.40005 0 270)
			(size 0 0)
			(layers "B.Cu" "B.Mask" "B.Paste")
			(net "GND")
		)
	)
)
